# SCM (Grand Teton) — schematic netlist excerpt (pin names and nets, part order shuffled) for the footprints in the layout excerpt that follows; sources: Cadence DE-HDL packaged netlist, KiCad conversion of 12092022_DA0F0TMDCD0_F0T_Management_Board_D_brd_V3_OCP.brd

C142  Q_CAP  10UF 25V 10% X6S  pkg C0805  page 54 : A = P1V8_AUX ; B = GND
R507  Q_RES  100 1% EMPTY  pkg 0402LF  page 48 : A = MB_JTAG_PLD_R_JTAGEN ; B = GND
PC214  Q_CAP  22UF 10V 20% X6S  pkg C0805  page 51 : A = P5V_AUX ; B = GND

(kicad_pcb
	(version 20260206)
	(generator "pcbnew")
	(generator_version "10.0")
	(general
		(thickness 1.6)
		(legacy_teardrops no)
	)
	(paper "A4")
	(title_block
		(title "12092022_DA0F0TMDCD0_F0T_Management_Board_D_brd_V3_OCP.brd")
		(comment 1 "Grand Teton / footprints 634-636 of 1440")
	)
	(layers
		(0 "F.Cu" signal "TOP")
		(4 "In1.Cu" signal "GND")
		(6 "In2.Cu" signal "IN1")
		(8 "In3.Cu" signal "GND1")
		(10 "In4.Cu" signal "IN2")
		(12 "In5.Cu" signal "VCC")
		(14 "In6.Cu" signal "VCC1")
		(16 "In7.Cu" signal "IN3")
		(18 "In8.Cu" signal "GND2")
		(20 "In9.Cu" signal "IN4")
		(22 "In10.Cu" signal "GND3")
		(2 "B.Cu" signal "BOTTOM")
		(9 "F.Adhes" user "F.Adhesive")
		(11 "B.Adhes" user "B.Adhesive")
		(13 "F.Paste" user "Package Geometry/Pastemask Top")
		(15 "B.Paste" user "Package Geometry/Pastemask Bottom")
		(5 "F.SilkS" user "Ref Des/Silkscreen Top")
		(7 "B.SilkS" user "Ref Des/Silkscreen Bottom")
		(1 "F.Mask" user "Board Geometry/Soldermask Top")
		(3 "B.Mask" user "Board Geometry/Soldermask Bottom")
		(17 "Dwgs.User" user "User.Drawings")
		(19 "Cmts.User" user "User.Comments")
		(21 "Eco1.User" user "User.Eco1")
		(23 "Eco2.User" user "User.Eco2")
		(25 "Edge.Cuts" user "Board Geometry/Outline")
		(27 "Margin" user)
		(31 "F.CrtYd" user "Package Geometry/Place Bound Top")
		(29 "B.CrtYd" user "Package Geometry/Place Bound Bottom")
		(35 "F.Fab" user "Ref Des/Assembly Top")
		(33 "B.Fab" user "Ref Des/Assembly Bottom")
	)
	(footprint ""
		(layer "F.Cu")
		(at 37.592 -53.086 180)
		(property "Reference" "C142"
			(at 0 0 180)
			(layer "F.SilkS")
			(hide yes)
			(effects
				(font
					(size 1.27 1.27)
				)
			)
		)
		(property "Value" ""
			(at 0 0 180)
			(layer "F.Fab")
			(effects
				(font
					(size 1.27 1.27)
				)
			)
		)
		(duplicate_pad_numbers_are_jumpers no)
		(fp_line
			(start 1.651 0.8382)
			(end -1.651 0.8382)
			(stroke
				(width 0.1524)
				(type default)
			)
			(layer "F.SilkS")
		)
		(fp_line
			(start 1.651 -0.8382)
			(end 1.651 0.8382)
			(stroke
				(width 0.1524)
				(type default)
			)
			(layer "F.SilkS")
		)
		(fp_line
			(start 0 0.8382)
			(end 0 -0.8382)
			(stroke
				(width 0.1524)
				(type default)
			)
			(layer "F.SilkS")
		)
		(fp_line
			(start -1.651 0.8382)
			(end -1.651 -0.8382)
			(stroke
				(width 0.1524)
				(type default)
			)
			(layer "F.SilkS")
		)
		(fp_line
			(start -1.651 -0.8382)
			(end 1.651 -0.8382)
			(stroke
				(width 0.1524)
				(type default)
			)
			(layer "F.SilkS")
		)
		(fp_line
			(start 1.55956 0.7366)
			(end 1.55956 -0.7366)
			(stroke
				(width 0.1)
				(type default)
			)
			(layer "F.Fab")
		)
		(fp_line
			(start 1.55956 -0.7366)
			(end 1.524 -0.7366)
			(stroke
				(width 0.1)
				(type default)
			)
			(layer "F.Fab")
		)
		(fp_line
			(start 1.524 0.7366)
			(end 1.55956 0.7366)
			(stroke
				(width 0.1)
				(type default)
			)
			(layer "F.Fab")
		)
		(fp_line
			(start 1.524 -0.7366)
			(end -1.524 -0.7366)
			(stroke
				(width 0.1)
				(type default)
			)
			(layer "F.Fab")
		)
		(fp_line
			(start -1.524 0.7366)
			(end 1.524 0.7366)
			(stroke
				(width 0.1)
				(type default)
			)
			(layer "F.Fab")
		)
		(fp_line
			(start -1.524 -0.7366)
			(end -1.55956 -0.7366)
			(stroke
				(width 0.1)
				(type default)
			)
			(layer "F.Fab")
		)
		(fp_line
			(start -1.55956 0.7366)
			(end -1.524 0.7366)
			(stroke
				(width 0.1)
				(type default)
			)
			(layer "F.Fab")
		)
		(fp_line
			(start -1.55956 -0.7366)
			(end -1.55956 0.7366)
			(stroke
				(width 0.1)
				(type default)
			)
			(layer "F.Fab")
		)
		(pad "1" smd rect
			(at -0.94996 0)
			(size 1.1176 1.3716)
			(layers "F.Cu" "F.Mask" "F.Paste")
			(net "P1V8_AUX")
		)
		(pad "2" smd rect
			(at 0.94996 0)
			(size 1.1176 1.3716)
			(layers "F.Cu" "F.Mask" "F.Paste")
			(net "GND")
		)
	)
	(footprint ""
		(layer "F.Cu")
		(at 9.271 -31.837122 -90)
		(property "Reference" "PC214"
			(at 0 0 270)
			(layer "F.SilkS")
			(hide yes)
			(effects
				(font
					(size 1.27 1.27)
				)
			)
		)
		(property "Value" ""
			(at 0 0 270)
			(layer "F.Fab")
			(effects
				(font
					(size 1.27 1.27)
				)
			)
		)
		(duplicate_pad_numbers_are_jumpers no)
		(fp_line
			(start -1.651 0.8382)
			(end -1.651 -0.8382)
			(stroke
				(width 0.1524)
				(type default)
			)
			(layer "F.SilkS")
		)
		(fp_line
			(start 0 0.8382)
			(end 0 -0.8382)
			(stroke
				(width 0.1524)
				(type default)
			)
			(layer "F.SilkS")
		)
		(fp_line
			(start 1.651 0.8382)
			(end -1.651 0.8382)
			(stroke
				(width 0.1524)
				(type default)
			)
			(layer "F.SilkS")
		)
		(fp_line
			(start -1.651 -0.8382)
			(end 1.651 -0.8382)
			(stroke
				(width 0.1524)
				(type default)
			)
			(layer "F.SilkS")
		)
		(fp_line
			(start 1.651 -0.8382)
			(end 1.651 0.8382)
			(stroke
				(width 0.1524)
				(type default)
			)
			(layer "F.SilkS")
		)
		(fp_line
			(start -1.55956 0.7366)
			(end -1.524 0.7366)
			(stroke
				(width 0.1)
				(type default)
			)
			(layer "F.Fab")
		)
		(fp_line
			(start -1.524 0.7366)
			(end 1.524 0.7366)
			(stroke
				(width 0.1)
				(type default)
			)
			(layer "F.Fab")
		)
		(fp_line
			(start 1.524 0.7366)
			(end 1.55956 0.7366)
			(stroke
				(width 0.1)
				(type default)
			)
			(layer "F.Fab")
		)
		(fp_line
			(start 1.55956 0.7366)
			(end 1.55956 -0.7366)
			(stroke
				(width 0.1)
				(type default)
			)
			(layer "F.Fab")
		)
		(fp_line
			(start -1.55956 -0.7366)
			(end -1.55956 0.7366)
			(stroke
				(width 0.1)
				(type default)
			)
			(layer "F.Fab")
		)
		(fp_line
			(start -1.524 -0.7366)
			(end -1.55956 -0.7366)
			(stroke
				(width 0.1)
				(type default)
			)
			(layer "F.Fab")
		)
		(fp_line
			(start 1.524 -0.7366)
			(end -1.524 -0.7366)
			(stroke
				(width 0.1)
				(type default)
			)
			(layer "F.Fab")
		)
		(fp_line
			(start 1.55956 -0.7366)
			(end 1.524 -0.7366)
			(stroke
				(width 0.1)
				(type default)
			)
			(layer "F.Fab")
		)
		(pad "1" smd rect
			(at -0.94996 0 90)
			(size 1.1176 1.3716)
			(layers "F.Cu" "F.Mask" "F.Paste")
			(net "P5V_AUX")
		)
		(pad "2" smd rect
			(at 0.94996 0 90)
			(size 1.1176 1.3716)
			(layers "F.Cu" "F.Mask" "F.Paste")
			(net "GND")
		)
	)
	(footprint ""
		(layer "F.Cu")
		(at 63.246 -81.788)
		(property "Reference" "R507"
			(at 0 0 0)
			(layer "F.SilkS")
			(hide yes)
			(effects
				(font
					(size 1.27 1.27)
				)
			)
		)
		(property "Value" ""
			(at 0 0 0)
			(layer "F.Fab")
			(effects
				(font
					(size 1.27 1.27)
				)
			)
		)
		(duplicate_pad_numbers_are_jumpers no)
		(fp_line
			(start -0.7874 -0.4064)
			(end 0.7874 -0.4064)
			(stroke
				(width 0.1524)
				(type default)
			)
			(layer "F.SilkS")
		)
		(fp_line
			(start -0.7874 0.4064)
			(end -0.7874 -0.4064)
			(stroke
				(width 0.1524)
				(type default)
			)
			(layer "F.SilkS")
		)
		(fp_line
			(start 0.7874 -0.4064)
			(end 0.7874 0.4064)
			(stroke
				(width 0.1524)
				(type default)
			)
			(layer "F.SilkS")
		)
		(fp_line
			(start 0.7874 0.4064)
			(end -0.7874 0.4064)
			(stroke
				(width 0.1524)
				(type default)
			)
			(layer "F.SilkS")
		)
		(fp_line
			(start -0.67945 -0.305054)
			(end -0.12065 -0.305054)
			(stroke
				(width 0.1)
				(type default)
			)
			(layer "F.Fab")
		)
		(fp_line
			(start -0.67945 0.3048)
			(end -0.67945 -0.305054)
			(stroke
				(width 0.1)
				(type default)
			)
			(layer "F.Fab")
		)
		(fp_line
			(start -0.12065 -0.305054)
			(end -0.12065 -0.2794)
			(stroke
				(width 0.1)
				(type default)
			)
			(layer "F.Fab")
		)
		(fp_line
			(start -0.12065 -0.2794)
			(end 0.12065 -0.2794)
			(stroke
				(width 0.1)
				(type default)
			)
			(layer "F.Fab")
		)
		(fp_line
			(start -0.12065 0.2794)
			(end -0.12065 0.3048)
			(stroke
				(width 0.1)
				(type default)
			)
			(layer "F.Fab")
		)
		(fp_line
			(start -0.12065 0.3048)
			(end -0.67945 0.3048)
			(stroke
				(width 0.1)
				(type default)
			)
			(layer "F.Fab")
		)
		(fp_line
			(start 0.120396 0.2794)
			(end -0.12065 0.2794)
			(stroke
				(width 0.1)
				(type default)
			)
			(layer "F.Fab")
		)
		(fp_line
			(start 0.120396 0.3048)
			(end 0.120396 0.2794)
			(stroke
				(width 0.1)
				(type default)
			)
			(layer "F.Fab")
		)
		(fp_line
			(start 0.12065 -0.3048)
			(end 0.67945 -0.3048)
			(stroke
				(width 0.1)
				(type default)
			)
			(layer "F.Fab")
		)
		(fp_line
			(start 0.12065 -0.2794)
			(end 0.12065 -0.3048)
			(stroke
				(width 0.1)
				(type default)
			)
			(layer "F.Fab")
		)
		(fp_line
			(start 0.67945 -0.3048)
			(end 0.67945 0.3048)
			(stroke
				(width 0.1)
				(type default)
			)
			(layer "F.Fab")
		)
		(fp_line
			(start 0.67945 0.3048)
			(end 0.120396 0.3048)
			(stroke
				(width 0.1)
				(type default)
			)
			(layer "F.Fab")
		)
		(pad "1" smd circle
			(at -0.40005 0)
			(size 0 0)
			(layers "F.Cu" "F.Mask" "F.Paste")
			(net "MB_JTAG_PLD_R_JTAGEN")
		)
		(pad "2" smd circle
			(at 0.40005 0)
			(size 0 0)
			(layers "F.Cu" "F.Mask" "F.Paste")
			(net "GND")
		)
	)
)
